# S9S_MB_2U (Grand Teton) — schematic netlist excerpt (pin names and nets, part order shuffled) for the footprints in the layout excerpt that follows; sources: Cadence DE-HDL packaged netlist, KiCad conversion of 03242023_DA0F0TMBIJ0_F0T_Motherboard_J_brd_V01_OCP.brd

R4748  Q_RES  0 5% EMPTY  pkg 0402LF  page 158 : A = HP_LVC3_OCP_V3_1_PWRGD_R2 ; B = OCP_SFF_AUX_PWR_EN_R2
R3630  Q_RES  0 5% CHIP  pkg 0402LF  page 163 : A = HP_LVC3_OCP_V3_2_EN ; B = P12V_OCP_V3_2_EN_2_R3

(kicad_pcb
	(version 20260206)
	(generator "pcbnew")
	(generator_version "10.0")
	(general
		(thickness 1.6)
		(legacy_teardrops no)
	)
	(paper "A4")
	(title_block
		(title "03242023_DA0F0TMBIJ0_F0T_Motherboard_J_brd_V01_OCP.brd")
		(comment 1 "Grand Teton / footprints 3894-3895 of 6105")
	)
	(layers
		(0 "F.Cu" signal "TOP")
		(4 "In1.Cu" signal "GND")
		(6 "In2.Cu" signal "IN1")
		(8 "In3.Cu" signal "GND1")
		(10 "In4.Cu" signal "IN2")
		(12 "In5.Cu" signal "GND2")
		(14 "In6.Cu" signal "IN3")
		(16 "In7.Cu" signal "GND3")
		(18 "In8.Cu" signal "VCC")
		(20 "In9.Cu" signal "VCC1")
		(22 "In10.Cu" signal "GND4")
		(24 "In11.Cu" signal "IN4")
		(26 "In12.Cu" signal "GND5")
		(28 "In13.Cu" signal "IN5")
		(30 "In14.Cu" signal "GND6")
		(32 "In15.Cu" signal "IN6")
		(34 "In16.Cu" signal "GND7")
		(2 "B.Cu" signal "BOTTOM")
		(9 "F.Adhes" user "F.Adhesive")
		(11 "B.Adhes" user "B.Adhesive")
		(13 "F.Paste" user "Package Geometry/Pastemask Top")
		(15 "B.Paste" user "Package Geometry/Pastemask Bottom")
		(5 "F.SilkS" user "Ref Des/Silkscreen Top")
		(7 "B.SilkS" user "Ref Des/Silkscreen Bottom")
		(1 "F.Mask" user "Board Geometry/Soldermask Top")
		(3 "B.Mask" user "Board Geometry/Soldermask Bottom")
		(17 "Dwgs.User" user "User.Drawings")
		(19 "Cmts.User" user "User.Comments")
		(21 "Eco1.User" user "User.Eco1")
		(23 "Eco2.User" user "User.Eco2")
		(25 "Edge.Cuts" user "Board Geometry/Outline")
		(27 "Margin" user)
		(31 "F.CrtYd" user "Package Geometry/Place Bound Top")
		(29 "B.CrtYd" user "Package Geometry/Place Bound Bottom")
		(35 "F.Fab" user "Ref Des/Assembly Top")
		(33 "B.Fab" user "Ref Des/Assembly Bottom")
	)
	(footprint ""
		(layer "F.Cu")
		(at 70.052438 -31.887922 -90)
		(property "Reference" "R3630"
			(at 0 0 270)
			(layer "F.SilkS")
			(hide yes)
			(effects
				(font
					(size 1.27 1.27)
				)
			)
		)
		(property "Value" ""
			(at 0 0 270)
			(layer "F.Fab")
			(effects
				(font
					(size 1.27 1.27)
				)
			)
		)
		(duplicate_pad_numbers_are_jumpers no)
		(fp_line
			(start -0.7874 0.4064)
			(end -0.7874 -0.4064)
			(stroke
				(width 0.1524)
				(type default)
			)
			(layer "F.SilkS")
		)
		(fp_line
			(start 0.7874 0.4064)
			(end -0.7874 0.4064)
			(stroke
				(width 0.1524)
				(type default)
			)
			(layer "F.SilkS")
		)
		(fp_line
			(start -0.7874 -0.4064)
			(end 0.7874 -0.4064)
			(stroke
				(width 0.1524)
				(type default)
			)
			(layer "F.SilkS")
		)
		(fp_line
			(start 0.7874 -0.4064)
			(end 0.7874 0.4064)
			(stroke
				(width 0.1524)
				(type default)
			)
			(layer "F.SilkS")
		)
		(fp_line
			(start -0.67945 0.3048)
			(end -0.67945 -0.305054)
			(stroke
				(width 0.1)
				(type default)
			)
			(layer "F.Fab")
		)
		(fp_line
			(start -0.12065 0.3048)
			(end -0.67945 0.3048)
			(stroke
				(width 0.1)
				(type default)
			)
			(layer "F.Fab")
		)
		(fp_line
			(start 0.120396 0.3048)
			(end 0.120396 0.2794)
			(stroke
				(width 0.1)
				(type default)
			)
			(layer "F.Fab")
		)
		(fp_line
			(start 0.67945 0.3048)
			(end 0.120396 0.3048)
			(stroke
				(width 0.1)
				(type default)
			)
			(layer "F.Fab")
		)
		(fp_line
			(start -0.12065 0.2794)
			(end -0.12065 0.3048)
			(stroke
				(width 0.1)
				(type default)
			)
			(layer "F.Fab")
		)
		(fp_line
			(start 0.120396 0.2794)
			(end -0.12065 0.2794)
			(stroke
				(width 0.1)
				(type default)
			)
			(layer "F.Fab")
		)
		(fp_line
			(start -0.12065 -0.2794)
			(end 0.12065 -0.2794)
			(stroke
				(width 0.1)
				(type default)
			)
			(layer "F.Fab")
		)
		(fp_line
			(start 0.12065 -0.2794)
			(end 0.12065 -0.3048)
			(stroke
				(width 0.1)
				(type default)
			)
			(layer "F.Fab")
		)
		(fp_line
			(start 0.12065 -0.3048)
			(end 0.67945 -0.3048)
			(stroke
				(width 0.1)
				(type default)
			)
			(layer "F.Fab")
		)
		(fp_line
			(start 0.67945 -0.3048)
			(end 0.67945 0.3048)
			(stroke
				(width 0.1)
				(type default)
			)
			(layer "F.Fab")
		)
		(fp_line
			(start -0.67945 -0.305054)
			(end -0.12065 -0.305054)
			(stroke
				(width 0.1)
				(type default)
			)
			(layer "F.Fab")
		)
		(fp_line
			(start -0.12065 -0.305054)
			(end -0.12065 -0.2794)
			(stroke
				(width 0.1)
				(type default)
			)
			(layer "F.Fab")
		)
		(pad "1" smd circle
			(at -0.40005 0 270)
			(size 0 0)
			(layers "F.Cu" "F.Mask" "F.Paste")
			(net "HP_LVC3_OCP_V3_2_EN")
		)
		(pad "2" smd circle
			(at 0.40005 0 270)
			(size 0 0)
			(layers "F.Cu" "F.Mask" "F.Paste")
			(net "P12V_OCP_V3_2_EN_2_R3")
		)
	)
	(footprint ""
		(layer "F.Cu")
		(at 441.52566 -106.38536 -90)
		(property "Reference" "R4748"
			(at 0 0 270)
			(layer "F.SilkS")
			(hide yes)
			(effects
				(font
					(size 1.27 1.27)
				)
			)
		)
		(property "Value" ""
			(at 0 0 270)
			(layer "F.Fab")
			(effects
				(font
					(size 1.27 1.27)
				)
			)
		)
		(duplicate_pad_numbers_are_jumpers no)
		(fp_line
			(start -0.7874 0.4064)
			(end -0.7874 -0.4064)
			(stroke
				(width 0.1524)
				(type default)
			)
			(layer "F.SilkS")
		)
		(fp_line
			(start 0.7874 0.4064)
			(end -0.7874 0.4064)
			(stroke
				(width 0.1524)
				(type default)
			)
			(layer "F.SilkS")
		)
		(fp_line
			(start -0.7874 -0.4064)
			(end 0.7874 -0.4064)
			(stroke
				(width 0.1524)
				(type default)
			)
			(layer "F.SilkS")
		)
		(fp_line
			(start 0.7874 -0.4064)
			(end 0.7874 0.4064)
			(stroke
				(width 0.1524)
				(type default)
			)
			(layer "F.SilkS")
		)
		(fp_line
			(start -0.67945 0.3048)
			(end -0.67945 -0.305054)
			(stroke
				(width 0.1)
				(type default)
			)
			(layer "F.Fab")
		)
		(fp_line
			(start -0.12065 0.3048)
			(end -0.67945 0.3048)
			(stroke
				(width 0.1)
				(type default)
			)
			(layer "F.Fab")
		)
		(fp_line
			(start 0.120396 0.3048)
			(end 0.120396 0.2794)
			(stroke
				(width 0.1)
				(type default)
			)
			(layer "F.Fab")
		)
		(fp_line
			(start 0.67945 0.3048)
			(end 0.120396 0.3048)
			(stroke
				(width 0.1)
				(type default)
			)
			(layer "F.Fab")
		)
		(fp_line
			(start -0.12065 0.2794)
			(end -0.12065 0.3048)
			(stroke
				(width 0.1)
				(type default)
			)
			(layer "F.Fab")
		)
		(fp_line
			(start 0.120396 0.2794)
			(end -0.12065 0.2794)
			(stroke
				(width 0.1)
				(type default)
			)
			(layer "F.Fab")
		)
		(fp_line
			(start -0.12065 -0.2794)
			(end 0.12065 -0.2794)
			(stroke
				(width 0.1)
				(type default)
			)
			(layer "F.Fab")
		)
		(fp_line
			(start 0.12065 -0.2794)
			(end 0.12065 -0.3048)
			(stroke
				(width 0.1)
				(type default)
			)
			(layer "F.Fab")
		)
		(fp_line
			(start 0.12065 -0.3048)
			(end 0.67945 -0.3048)
			(stroke
				(width 0.1)
				(type default)
			)
			(layer "F.Fab")
		)
		(fp_line
			(start 0.67945 -0.3048)
			(end 0.67945 0.3048)
			(stroke
				(width 0.1)
				(type default)
			)
			(layer "F.Fab")
		)
		(fp_line
			(start -0.67945 -0.305054)
			(end -0.12065 -0.305054)
			(stroke
				(width 0.1)
				(type default)
			)
			(layer "F.Fab")
		)
		(fp_line
			(start -0.12065 -0.305054)
			(end -0.12065 -0.2794)
			(stroke
				(width 0.1)
				(type default)
			)
			(layer "F.Fab")
		)
		(pad "1" smd circle
			(at -0.40005 0 270)
			(size 0 0)
			(layers "F.Cu" "F.Mask" "F.Paste")
			(net "HP_LVC3_OCP_V3_1_PWRGD_R2")
		)
		(pad "2" smd circle
			(at 0.40005 0 270)
			(size 0 0)
			(layers "F.Cu" "F.Mask" "F.Paste")
			(net "OCP_SFF_AUX_PWR_EN_R2")
		)
	)
)
